# T6G (Grand Teton) — schematic netlist excerpt (pin names and nets, part order shuffled) for the footprints in the layout excerpt that follows; sources: Cadence DE-HDL packaged netlist, KiCad conversion of 04192023_DAF0TMB3IC0_F0TG_MB_C_brd_V02_OCP.brd

R6086  Q_RES  10K 1% EMPTY  pkg 0402LF  page 200 : A = PVDDIO_P0_EN_R ; B = GND
R8022  Q_RES  560 1% CHIP  pkg 0402LF  page 256 : A = LED_P12V_AUX_R1 ; B = LED_P12V_AUX_R2

(kicad_pcb
	(version 20260206)
	(generator "pcbnew")
	(generator_version "10.0")
	(general
		(thickness 1.6)
		(legacy_teardrops no)
	)
	(paper "A4")
	(title_block
		(title "04192023_DAF0TMB3IC0_F0TG_MB_C_brd_V02_OCP.brd")
		(comment 1 "Grand Teton / footprints 510-511 of 8354")
	)
	(layers
		(0 "F.Cu" signal "TOP")
		(4 "In1.Cu" signal "GND")
		(6 "In2.Cu" signal "IN1")
		(8 "In3.Cu" signal "GND1")
		(10 "In4.Cu" signal "IN2")
		(12 "In5.Cu" signal "GND2")
		(14 "In6.Cu" signal "IN3")
		(16 "In7.Cu" signal "GND3")
		(18 "In8.Cu" signal "VCC")
		(20 "In9.Cu" signal "VCC1")
		(22 "In10.Cu" signal "GND4")
		(24 "In11.Cu" signal "IN4")
		(26 "In12.Cu" signal "GND5")
		(28 "In13.Cu" signal "IN5")
		(30 "In14.Cu" signal "GND6")
		(32 "In15.Cu" signal "IN6")
		(34 "In16.Cu" signal "GND7")
		(2 "B.Cu" signal "BOTTOM")
		(9 "F.Adhes" user "F.Adhesive")
		(11 "B.Adhes" user "B.Adhesive")
		(13 "F.Paste" user "Package Geometry/Pastemask Top")
		(15 "B.Paste" user "Package Geometry/Pastemask Bottom")
		(5 "F.SilkS" user "Ref Des/Silkscreen Top")
		(7 "B.SilkS" user "Ref Des/Silkscreen Bottom")
		(1 "F.Mask" user "Board Geometry/Soldermask Top")
		(3 "B.Mask" user "Board Geometry/Soldermask Bottom")
		(17 "Dwgs.User" user "User.Drawings")
		(19 "Cmts.User" user "User.Comments")
		(21 "Eco1.User" user "User.Eco1")
		(23 "Eco2.User" user "User.Eco2")
		(25 "Edge.Cuts" user "Board Geometry/Outline")
		(27 "Margin" user)
		(31 "F.CrtYd" user "Package Geometry/Place Bound Top")
		(29 "B.CrtYd" user "Package Geometry/Place Bound Bottom")
		(35 "F.Fab" user "Ref Des/Assembly Top")
		(33 "B.Fab" user "Ref Des/Assembly Bottom")
	)
	(footprint ""
		(layer "F.Cu")
		(at 364.139226 -62.0903)
		(property "Reference" "R8022"
			(at 0 0 0)
			(layer "F.SilkS")
			(hide yes)
			(effects
				(font
					(size 1.27 1.27)
				)
			)
		)
		(property "Value" ""
			(at 0 0 0)
			(layer "F.Fab")
			(effects
				(font
					(size 1.27 1.27)
				)
			)
		)
		(duplicate_pad_numbers_are_jumpers no)
		(fp_line
			(start -0.7874 -0.4064)
			(end 0.7874 -0.4064)
			(stroke
				(width 0.1524)
				(type default)
			)
			(layer "F.SilkS")
		)
		(fp_line
			(start -0.7874 0.4064)
			(end -0.7874 -0.4064)
			(stroke
				(width 0.1524)
				(type default)
			)
			(layer "F.SilkS")
		)
		(fp_line
			(start 0.7874 -0.4064)
			(end 0.7874 0.4064)
			(stroke
				(width 0.1524)
				(type default)
			)
			(layer "F.SilkS")
		)
		(fp_line
			(start 0.7874 0.4064)
			(end -0.7874 0.4064)
			(stroke
				(width 0.1524)
				(type default)
			)
			(layer "F.SilkS")
		)
		(fp_line
			(start -0.67945 -0.305054)
			(end -0.12065 -0.305054)
			(stroke
				(width 0.1)
				(type default)
			)
			(layer "F.Fab")
		)
		(fp_line
			(start -0.67945 0.3048)
			(end -0.67945 -0.305054)
			(stroke
				(width 0.1)
				(type default)
			)
			(layer "F.Fab")
		)
		(fp_line
			(start -0.12065 -0.305054)
			(end -0.12065 -0.2794)
			(stroke
				(width 0.1)
				(type default)
			)
			(layer "F.Fab")
		)
		(fp_line
			(start -0.12065 -0.2794)
			(end 0.12065 -0.2794)
			(stroke
				(width 0.1)
				(type default)
			)
			(layer "F.Fab")
		)
		(fp_line
			(start -0.12065 0.2794)
			(end -0.12065 0.3048)
			(stroke
				(width 0.1)
				(type default)
			)
			(layer "F.Fab")
		)
		(fp_line
			(start -0.12065 0.3048)
			(end -0.67945 0.3048)
			(stroke
				(width 0.1)
				(type default)
			)
			(layer "F.Fab")
		)
		(fp_line
			(start 0.120396 0.2794)
			(end -0.12065 0.2794)
			(stroke
				(width 0.1)
				(type default)
			)
			(layer "F.Fab")
		)
		(fp_line
			(start 0.120396 0.3048)
			(end 0.120396 0.2794)
			(stroke
				(width 0.1)
				(type default)
			)
			(layer "F.Fab")
		)
		(fp_line
			(start 0.12065 -0.3048)
			(end 0.67945 -0.3048)
			(stroke
				(width 0.1)
				(type default)
			)
			(layer "F.Fab")
		)
		(fp_line
			(start 0.12065 -0.2794)
			(end 0.12065 -0.3048)
			(stroke
				(width 0.1)
				(type default)
			)
			(layer "F.Fab")
		)
		(fp_line
			(start 0.67945 -0.3048)
			(end 0.67945 0.3048)
			(stroke
				(width 0.1)
				(type default)
			)
			(layer "F.Fab")
		)
		(fp_line
			(start 0.67945 0.3048)
			(end 0.120396 0.3048)
			(stroke
				(width 0.1)
				(type default)
			)
			(layer "F.Fab")
		)
		(pad "1" smd circle
			(at -0.40005 0)
			(size 0 0)
			(layers "F.Cu" "F.Mask" "F.Paste")
			(net "LED_P12V_AUX_R1")
		)
		(pad "2" smd circle
			(at 0.40005 0)
			(size 0 0)
			(layers "F.Cu" "F.Mask" "F.Paste")
			(net "LED_P12V_AUX_R2")
		)
	)
	(footprint ""
		(layer "F.Cu")
		(at 287.996884 -370.318792 -90)
		(property "Reference" "R6086"
			(at 0 0 270)
			(layer "F.SilkS")
			(hide yes)
			(effects
				(font
					(size 1.27 1.27)
				)
			)
		)
		(property "Value" ""
			(at 0 0 270)
			(layer "F.Fab")
			(effects
				(font
					(size 1.27 1.27)
				)
			)
		)
		(duplicate_pad_numbers_are_jumpers no)
		(fp_line
			(start -0.7874 0.4064)
			(end -0.7874 -0.4064)
			(stroke
				(width 0.1524)
				(type default)
			)
			(layer "F.SilkS")
		)
		(fp_line
			(start 0.7874 0.4064)
			(end -0.7874 0.4064)
			(stroke
				(width 0.1524)
				(type default)
			)
			(layer "F.SilkS")
		)
		(fp_line
			(start -0.7874 -0.4064)
			(end 0.7874 -0.4064)
			(stroke
				(width 0.1524)
				(type default)
			)
			(layer "F.SilkS")
		)
		(fp_line
			(start 0.7874 -0.4064)
			(end 0.7874 0.4064)
			(stroke
				(width 0.1524)
				(type default)
			)
			(layer "F.SilkS")
		)
		(fp_line
			(start -0.67945 0.3048)
			(end -0.67945 -0.305054)
			(stroke
				(width 0.1)
				(type default)
			)
			(layer "F.Fab")
		)
		(fp_line
			(start -0.12065 0.3048)
			(end -0.67945 0.3048)
			(stroke
				(width 0.1)
				(type default)
			)
			(layer "F.Fab")
		)
		(fp_line
			(start 0.120396 0.3048)
			(end 0.120396 0.2794)
			(stroke
				(width 0.1)
				(type default)
			)
			(layer "F.Fab")
		)
		(fp_line
			(start 0.67945 0.3048)
			(end 0.120396 0.3048)
			(stroke
				(width 0.1)
				(type default)
			)
			(layer "F.Fab")
		)
		(fp_line
			(start -0.12065 0.2794)
			(end -0.12065 0.3048)
			(stroke
				(width 0.1)
				(type default)
			)
			(layer "F.Fab")
		)
		(fp_line
			(start 0.120396 0.2794)
			(end -0.12065 0.2794)
			(stroke
				(width 0.1)
				(type default)
			)
			(layer "F.Fab")
		)
		(fp_line
			(start -0.12065 -0.2794)
			(end 0.12065 -0.2794)
			(stroke
				(width 0.1)
				(type default)
			)
			(layer "F.Fab")
		)
		(fp_line
			(start 0.12065 -0.2794)
			(end 0.12065 -0.3048)
			(stroke
				(width 0.1)
				(type default)
			)
			(layer "F.Fab")
		)
		(fp_line
			(start 0.12065 -0.3048)
			(end 0.67945 -0.3048)
			(stroke
				(width 0.1)
				(type default)
			)
			(layer "F.Fab")
		)
		(fp_line
			(start 0.67945 -0.3048)
			(end 0.67945 0.3048)
			(stroke
				(width 0.1)
				(type default)
			)
			(layer "F.Fab")
		)
		(fp_line
			(start -0.67945 -0.305054)
			(end -0.12065 -0.305054)
			(stroke
				(width 0.1)
				(type default)
			)
			(layer "F.Fab")
		)
		(fp_line
			(start -0.12065 -0.305054)
			(end -0.12065 -0.2794)
			(stroke
				(width 0.1)
				(type default)
			)
			(layer "F.Fab")
		)
		(pad "1" smd circle
			(at -0.40005 0 270)
			(size 0 0)
			(layers "F.Cu" "F.Mask" "F.Paste")
			(net "PVDDIO_P0_EN_R")
		)
		(pad "2" smd circle
			(at 0.40005 0 270)
			(size 0 0)
			(layers "F.Cu" "F.Mask" "F.Paste")
			(net "GND")
		)
	)
)
